(kicad_pcb
	(version 20260206)
	(generator "pcbnew")
	(generator_version "10.0")
	(general
		(thickness 1.6)
		(legacy_teardrops no)
	)
	(paper "A4")
	(title_block
		(title "04192023_DAF0TMB3IC0_F0TG_MB_C_brd_V02_OCP.brd")
		(comment 1 "Grand Teton / footprints 7377-7383 of 8354")
	)
	(layers
		(0 "F.Cu" signal "TOP")
		(4 "In1.Cu" signal "GND")
		(6 "In2.Cu" signal "IN1")
		(8 "In3.Cu" signal "GND1")
		(10 "In4.Cu" signal "IN2")
		(12 "In5.Cu" signal "GND2")
		(14 "In6.Cu" signal "IN3")
		(16 "In7.Cu" signal "GND3")
		(18 "In8.Cu" signal "VCC")
		(20 "In9.Cu" signal "VCC1")
		(22 "In10.Cu" signal "GND4")
		(24 "In11.Cu" signal "IN4")
		(26 "In12.Cu" signal "GND5")
		(28 "In13.Cu" signal "IN5")
		(30 "In14.Cu" signal "GND6")
		(32 "In15.Cu" signal "IN6")
		(34 "In16.Cu" signal "GND7")
		(2 "B.Cu" signal "BOTTOM")
		(9 "F.Adhes" user "F.Adhesive")
		(11 "B.Adhes" user "B.Adhesive")
		(13 "F.Paste" user "Package Geometry/Pastemask Top")
		(15 "B.Paste" user "Package Geometry/Pastemask Bottom")
		(5 "F.SilkS" user "Ref Des/Silkscreen Top")
		(7 "B.SilkS" user "Ref Des/Silkscreen Bottom")
		(1 "F.Mask" user "Board Geometry/Soldermask Top")
		(3 "B.Mask" user "Board Geometry/Soldermask Bottom")
		(17 "Dwgs.User" user "User.Drawings")
		(19 "Cmts.User" user "User.Comments")
		(21 "Eco1.User" user "User.Eco1")
		(23 "Eco2.User" user "User.Eco2")
		(25 "Edge.Cuts" user "Board Geometry/Outline")
		(27 "Margin" user)
		(31 "F.CrtYd" user "Package Geometry/Place Bound Top")
		(29 "B.CrtYd" user "Package Geometry/Place Bound Bottom")
		(35 "F.Fab" user "Ref Des/Assembly Top")
		(33 "B.Fab" user "Ref Des/Assembly Bottom")
	)
	(footprint ""
		(layer "B.Cu")
		(at 156.17063 -13.762228 90)
		(property "Reference" "R2413"
			(at 0 0 90)
			(layer "B.SilkS")
			(hide yes)
			(effects
				(font
					(size 1.27 1.27)
				)
				(justify mirror)
			)
		)
		(property "Value" ""
			(at 0 0 90)
			(layer "B.Fab")
			(effects
				(font
					(size 1.27 1.27)
				)
				(justify mirror)
			)
		)
		(duplicate_pad_numbers_are_jumpers no)
		(fp_line
			(start 0.7874 -0.4064)
			(end -0.7874 -0.4064)
			(stroke
				(width 0.1524)
				(type default)
			)
			(layer "B.SilkS")
		)
		(fp_line
			(start -0.7874 -0.4064)
			(end -0.7874 0.4064)
			(stroke
				(width 0.1524)
				(type default)
			)
			(layer "B.SilkS")
		)
		(fp_line
			(start 0.7874 0.4064)
			(end 0.7874 -0.4064)
			(stroke
				(width 0.1524)
				(type default)
			)
			(layer "B.SilkS")
		)
		(fp_line
			(start -0.7874 0.4064)
			(end 0.7874 0.4064)
			(stroke
				(width 0.1524)
				(type default)
			)
			(layer "B.SilkS")
		)
		(fp_line
			(start 0.67945 -0.305054)
			(end 0.12065 -0.305054)
			(stroke
				(width 0.1)
				(type default)
			)
			(layer "B.Fab")
		)
		(fp_line
			(start 0.12065 -0.305054)
			(end 0.12065 -0.2794)
			(stroke
				(width 0.1)
				(type default)
			)
			(layer "B.Fab")
		)
		(fp_line
			(start -0.12065 -0.3048)
			(end -0.67945 -0.3048)
			(stroke
				(width 0.1)
				(type default)
			)
			(layer "B.Fab")
		)
		(fp_line
			(start -0.67945 -0.3048)
			(end -0.67945 0.3048)
			(stroke
				(width 0.1)
				(type default)
			)
			(layer "B.Fab")
		)
		(fp_line
			(start 0.12065 -0.2794)
			(end -0.12065 -0.2794)
			(stroke
				(width 0.1)
				(type default)
			)
			(layer "B.Fab")
		)
		(fp_line
			(start -0.12065 -0.2794)
			(end -0.12065 -0.3048)
			(stroke
				(width 0.1)
				(type default)
			)
			(layer "B.Fab")
		)
		(fp_line
			(start 0.12065 0.2794)
			(end 0.12065 0.3048)
			(stroke
				(width 0.1)
				(type default)
			)
			(layer "B.Fab")
		)
		(fp_line
			(start -0.120396 0.2794)
			(end 0.12065 0.2794)
			(stroke
				(width 0.1)
				(type default)
			)
			(layer "B.Fab")
		)
		(fp_line
			(start 0.67945 0.3048)
			(end 0.67945 -0.305054)
			(stroke
				(width 0.1)
				(type default)
			)
			(layer "B.Fab")
		)
		(fp_line
			(start 0.12065 0.3048)
			(end 0.67945 0.3048)
			(stroke
				(width 0.1)
				(type default)
			)
			(layer "B.Fab")
		)
		(fp_line
			(start -0.120396 0.3048)
			(end -0.120396 0.2794)
			(stroke
				(width 0.1)
				(type default)
			)
			(layer "B.Fab")
		)
		(fp_line
			(start -0.67945 0.3048)
			(end -0.120396 0.3048)
			(stroke
				(width 0.1)
				(type default)
			)
			(layer "B.Fab")
		)
		(pad "1" smd circle
			(at 0.40005 0 270)
			(size 0 0)
			(layers "B.Cu" "B.Mask" "B.Paste")
			(net "SMB_2_BMC_GPU_SCL")
		)
		(pad "2" smd circle
			(at -0.40005 0 270)
			(size 0 0)
			(layers "B.Cu" "B.Mask" "B.Paste")
			(net "SMB_PCIE2_3V3AUX_SCL_R0")
		)
	)
	(footprint ""
		(layer "B.Cu")
		(at 182.860442 -193.996564)
		(property "Reference" "C168"
			(at 0 0 0)
			(layer "B.SilkS")
			(hide yes)
			(effects
				(font
					(size 1.27 1.27)
				)
				(justify mirror)
			)
		)
		(property "Value" ""
			(at 0 0 0)
			(layer "B.Fab")
			(effects
				(font
					(size 1.27 1.27)
				)
				(justify mirror)
			)
		)
		(duplicate_pad_numbers_are_jumpers no)
		(fp_line
			(start -0.7874 -0.4064)
			(end -0.7874 0.4064)
			(stroke
				(width 0.1524)
				(type default)
			)
			(layer "B.SilkS")
		)
		(fp_line
			(start -0.7874 0.4064)
			(end 0.7874 0.4064)
			(stroke
				(width 0.1524)
				(type default)
			)
			(layer "B.SilkS")
		)
		(fp_line
			(start 0.7874 -0.4064)
			(end -0.7874 -0.4064)
			(stroke
				(width 0.1524)
				(type default)
			)
			(layer "B.SilkS")
		)
		(fp_line
			(start 0.7874 0.4064)
			(end 0.7874 -0.4064)
			(stroke
				(width 0.1524)
				(type default)
			)
			(layer "B.SilkS")
		)
		(fp_line
			(start -0.67945 -0.3048)
			(end -0.67945 0.3048)
			(stroke
				(width 0.1)
				(type default)
			)
			(layer "B.Fab")
		)
		(fp_line
			(start -0.67945 0.3048)
			(end -0.120396 0.3048)
			(stroke
				(width 0.1)
				(type default)
			)
			(layer "B.Fab")
		)
		(fp_line
			(start -0.12065 -0.3048)
			(end -0.67945 -0.3048)
			(stroke
				(width 0.1)
				(type default)
			)
			(layer "B.Fab")
		)
		(fp_line
			(start -0.12065 -0.2794)
			(end -0.12065 -0.3048)
			(stroke
				(width 0.1)
				(type default)
			)
			(layer "B.Fab")
		)
		(fp_line
			(start -0.120396 0.2794)
			(end 0.12065 0.2794)
			(stroke
				(width 0.1)
				(type default)
			)
			(layer "B.Fab")
		)
		(fp_line
			(start -0.120396 0.3048)
			(end -0.120396 0.2794)
			(stroke
				(width 0.1)
				(type default)
			)
			(layer "B.Fab")
		)
		(fp_line
			(start 0.12065 -0.305054)
			(end 0.12065 -0.2794)
			(stroke
				(width 0.1)
				(type default)
			)
			(layer "B.Fab")
		)
		(fp_line
			(start 0.12065 -0.2794)
			(end -0.12065 -0.2794)
			(stroke
				(width 0.1)
				(type default)
			)
			(layer "B.Fab")
		)
		(fp_line
			(start 0.12065 0.2794)
			(end 0.12065 0.3048)
			(stroke
				(width 0.1)
				(type default)
			)
			(layer "B.Fab")
		)
		(fp_line
			(start 0.12065 0.3048)
			(end 0.67945 0.3048)
			(stroke
				(width 0.1)
				(type default)
			)
			(layer "B.Fab")
		)
		(fp_line
			(start 0.67945 -0.305054)
			(end 0.12065 -0.305054)
			(stroke
				(width 0.1)
				(type default)
			)
			(layer "B.Fab")
		)
		(fp_line
			(start 0.67945 0.3048)
			(end 0.67945 -0.305054)
			(stroke
				(width 0.1)
				(type default)
			)
			(layer "B.Fab")
		)
		(pad "1" smd circle
			(at 0.40005 0 180)
			(size 0 0)
			(layers "B.Cu" "B.Mask" "B.Paste")
			(net "P3V3_AUX")
		)
		(pad "2" smd circle
			(at -0.40005 0 180)
			(size 0 0)
			(layers "B.Cu" "B.Mask" "B.Paste")
			(net "GND")
		)
	)
	(footprint ""
		(layer "B.Cu")
		(at 242.443 -234.061 90)
		(property "Reference" "R1159"
			(at 0 0 90)
			(layer "B.SilkS")
			(hide yes)
			(effects
				(font
					(size 1.27 1.27)
				)
				(justify mirror)
			)
		)
		(property "Value" ""
			(at 0 0 90)
			(layer "B.Fab")
			(effects
				(font
					(size 1.27 1.27)
				)
				(justify mirror)
			)
		)
		(duplicate_pad_numbers_are_jumpers no)
		(fp_line
			(start 0.7874 -0.4064)
			(end -0.7874 -0.4064)
			(stroke
				(width 0.1524)
				(type default)
			)
			(layer "B.SilkS")
		)
		(fp_line
			(start -0.7874 -0.4064)
			(end -0.7874 0.4064)
			(stroke
				(width 0.1524)
				(type default)
			)
			(layer "B.SilkS")
		)
		(fp_line
			(start 0.7874 0.4064)
			(end 0.7874 -0.4064)
			(stroke
				(width 0.1524)
				(type default)
			)
			(layer "B.SilkS")
		)
		(fp_line
			(start -0.7874 0.4064)
			(end 0.7874 0.4064)
			(stroke
				(width 0.1524)
				(type default)
			)
			(layer "B.SilkS")
		)
		(fp_line
			(start 0.67945 -0.305054)
			(end 0.12065 -0.305054)
			(stroke
				(width 0.1)
				(type default)
			)
			(layer "B.Fab")
		)
		(fp_line
			(start 0.12065 -0.305054)
			(end 0.12065 -0.2794)
			(stroke
				(width 0.1)
				(type default)
			)
			(layer "B.Fab")
		)
		(fp_line
			(start -0.12065 -0.3048)
			(end -0.67945 -0.3048)
			(stroke
				(width 0.1)
				(type default)
			)
			(layer "B.Fab")
		)
		(fp_line
			(start -0.67945 -0.3048)
			(end -0.67945 0.3048)
			(stroke
				(width 0.1)
				(type default)
			)
			(layer "B.Fab")
		)
		(fp_line
			(start 0.12065 -0.2794)
			(end -0.12065 -0.2794)
			(stroke
				(width 0.1)
				(type default)
			)
			(layer "B.Fab")
		)
		(fp_line
			(start -0.12065 -0.2794)
			(end -0.12065 -0.3048)
			(stroke
				(width 0.1)
				(type default)
			)
			(layer "B.Fab")
		)
		(fp_line
			(start 0.12065 0.2794)
			(end 0.12065 0.3048)
			(stroke
				(width 0.1)
				(type default)
			)
			(layer "B.Fab")
		)
		(fp_line
			(start -0.120396 0.2794)
			(end 0.12065 0.2794)
			(stroke
				(width 0.1)
				(type default)
			)
			(layer "B.Fab")
		)
		(fp_line
			(start 0.67945 0.3048)
			(end 0.67945 -0.305054)
			(stroke
				(width 0.1)
				(type default)
			)
			(layer "B.Fab")
		)
		(fp_line
			(start 0.12065 0.3048)
			(end 0.67945 0.3048)
			(stroke
				(width 0.1)
				(type default)
			)
			(layer "B.Fab")
		)
		(fp_line
			(start -0.120396 0.3048)
			(end -0.120396 0.2794)
			(stroke
				(width 0.1)
				(type default)
			)
			(layer "B.Fab")
		)
		(fp_line
			(start -0.67945 0.3048)
			(end -0.120396 0.3048)
			(stroke
				(width 0.1)
				(type default)
			)
			(layer "B.Fab")
		)
		(pad "1" smd circle
			(at 0.40005 0 270)
			(size 0 0)
			(layers "B.Cu" "B.Mask" "B.Paste")
			(net "SMB_CPU0_SEC_R_SCL")
		)
		(pad "2" smd circle
			(at -0.40005 0 270)
			(size 0 0)
			(layers "B.Cu" "B.Mask" "B.Paste")
			(net "SMB_CPU0_SEC_SCL")
		)
	)
	(footprint ""
		(layer "B.Cu")
		(at 117.996462 -170.864276 90)
		(property "Reference" "PR205"
			(at 0 0 90)
			(layer "B.SilkS")
			(hide yes)
			(effects
				(font
					(size 1.27 1.27)
				)
				(justify mirror)
			)
		)
		(property "Value" ""
			(at 0 0 90)
			(layer "B.Fab")
			(effects
				(font
					(size 1.27 1.27)
				)
				(justify mirror)
			)
		)
		(duplicate_pad_numbers_are_jumpers no)
		(fp_line
			(start 0.7874 -0.4064)
			(end -0.7874 -0.4064)
			(stroke
				(width 0.1524)
				(type default)
			)
			(layer "B.SilkS")
		)
		(fp_line
			(start -0.7874 -0.4064)
			(end -0.7874 0.4064)
			(stroke
				(width 0.1524)
				(type default)
			)
			(layer "B.SilkS")
		)
		(fp_line
			(start 0.7874 0.4064)
			(end 0.7874 -0.4064)
			(stroke
				(width 0.1524)
				(type default)
			)
			(layer "B.SilkS")
		)
		(fp_line
			(start -0.7874 0.4064)
			(end 0.7874 0.4064)
			(stroke
				(width 0.1524)
				(type default)
			)
			(layer "B.SilkS")
		)
		(fp_line
			(start 0.67945 -0.305054)
			(end 0.12065 -0.305054)
			(stroke
				(width 0.1)
				(type default)
			)
			(layer "B.Fab")
		)
		(fp_line
			(start 0.12065 -0.305054)
			(end 0.12065 -0.2794)
			(stroke
				(width 0.1)
				(type default)
			)
			(layer "B.Fab")
		)
		(fp_line
			(start -0.12065 -0.3048)
			(end -0.67945 -0.3048)
			(stroke
				(width 0.1)
				(type default)
			)
			(layer "B.Fab")
		)
		(fp_line
			(start -0.67945 -0.3048)
			(end -0.67945 0.3048)
			(stroke
				(width 0.1)
				(type default)
			)
			(layer "B.Fab")
		)
		(fp_line
			(start 0.12065 -0.2794)
			(end -0.12065 -0.2794)
			(stroke
				(width 0.1)
				(type default)
			)
			(layer "B.Fab")
		)
		(fp_line
			(start -0.12065 -0.2794)
			(end -0.12065 -0.3048)
			(stroke
				(width 0.1)
				(type default)
			)
			(layer "B.Fab")
		)
		(fp_line
			(start 0.12065 0.2794)
			(end 0.12065 0.3048)
			(stroke
				(width 0.1)
				(type default)
			)
			(layer "B.Fab")
		)
		(fp_line
			(start -0.120396 0.2794)
			(end 0.12065 0.2794)
			(stroke
				(width 0.1)
				(type default)
			)
			(layer "B.Fab")
		)
		(fp_line
			(start 0.67945 0.3048)
			(end 0.67945 -0.305054)
			(stroke
				(width 0.1)
				(type default)
			)
			(layer "B.Fab")
		)
		(fp_line
			(start 0.12065 0.3048)
			(end 0.67945 0.3048)
			(stroke
				(width 0.1)
				(type default)
			)
			(layer "B.Fab")
		)
		(fp_line
			(start -0.120396 0.3048)
			(end -0.120396 0.2794)
			(stroke
				(width 0.1)
				(type default)
			)
			(layer "B.Fab")
		)
		(fp_line
			(start -0.67945 0.3048)
			(end -0.120396 0.3048)
			(stroke
				(width 0.1)
				(type default)
			)
			(layer "B.Fab")
		)
		(pad "1" smd circle
			(at 0.40005 0 270)
			(size 0 0)
			(layers "B.Cu" "B.Mask" "B.Paste")
			(net "PVDDCR_CPU0_P1_PVCC")
		)
		(pad "2" smd circle
			(at -0.40005 0 270)
			(size 0 0)
			(layers "B.Cu" "B.Mask" "B.Paste")
			(net "PVDDCR_SOC_P1_VCC1")
		)
	)
	(footprint ""
		(layer "B.Cu")
		(at 47.538386 -190.948564 180)
		(property "Reference" "R304"
			(at 0 0 0)
			(layer "B.SilkS")
			(hide yes)
			(effects
				(font
					(size 1.27 1.27)
				)
				(justify mirror)
			)
		)
		(property "Value" ""
			(at 0 0 0)
			(layer "B.Fab")
			(effects
				(font
					(size 1.27 1.27)
				)
				(justify mirror)
			)
		)
		(duplicate_pad_numbers_are_jumpers no)
		(fp_line
			(start 0.7874 0.4064)
			(end 0.7874 -0.4064)
			(stroke
				(width 0.1524)
				(type default)
			)
			(layer "B.SilkS")
		)
		(fp_line
			(start 0.7874 -0.4064)
			(end -0.7874 -0.4064)
			(stroke
				(width 0.1524)
				(type default)
			)
			(layer "B.SilkS")
		)
		(fp_line
			(start -0.7874 0.4064)
			(end 0.7874 0.4064)
			(stroke
				(width 0.1524)
				(type default)
			)
			(layer "B.SilkS")
		)
		(fp_line
			(start -0.7874 -0.4064)
			(end -0.7874 0.4064)
			(stroke
				(width 0.1524)
				(type default)
			)
			(layer "B.SilkS")
		)
		(fp_line
			(start 0.67945 0.3048)
			(end 0.67945 -0.305054)
			(stroke
				(width 0.1)
				(type default)
			)
			(layer "B.Fab")
		)
		(fp_line
			(start 0.67945 -0.305054)
			(end 0.12065 -0.305054)
			(stroke
				(width 0.1)
				(type default)
			)
			(layer "B.Fab")
		)
		(fp_line
			(start 0.12065 0.3048)
			(end 0.67945 0.3048)
			(stroke
				(width 0.1)
				(type default)
			)
			(layer "B.Fab")
		)
		(fp_line
			(start 0.12065 0.2794)
			(end 0.12065 0.3048)
			(stroke
				(width 0.1)
				(type default)
			)
			(layer "B.Fab")
		)
		(fp_line
			(start 0.12065 -0.2794)
			(end -0.12065 -0.2794)
			(stroke
				(width 0.1)
				(type default)
			)
			(layer "B.Fab")
		)
		(fp_line
			(start 0.12065 -0.305054)
			(end 0.12065 -0.2794)
			(stroke
				(width 0.1)
				(type default)
			)
			(layer "B.Fab")
		)
		(fp_line
			(start -0.120396 0.3048)
			(end -0.120396 0.2794)
			(stroke
				(width 0.1)
				(type default)
			)
			(layer "B.Fab")
		)
		(fp_line
			(start -0.120396 0.2794)
			(end 0.12065 0.2794)
			(stroke
				(width 0.1)
				(type default)
			)
			(layer "B.Fab")
		)
		(fp_line
			(start -0.12065 -0.2794)
			(end -0.12065 -0.3048)
			(stroke
				(width 0.1)
				(type default)
			)
			(layer "B.Fab")
		)
		(fp_line
			(start -0.12065 -0.3048)
			(end -0.67945 -0.3048)
			(stroke
				(width 0.1)
				(type default)
			)
			(layer "B.Fab")
		)
		(fp_line
			(start -0.67945 0.3048)
			(end -0.120396 0.3048)
			(stroke
				(width 0.1)
				(type default)
			)
			(layer "B.Fab")
		)
		(fp_line
			(start -0.67945 -0.3048)
			(end -0.67945 0.3048)
			(stroke
				(width 0.1)
				(type default)
			)
			(layer "B.Fab")
		)
		(pad "1" smd circle
			(at 0.40005 0)
			(size 0 0)
			(layers "B.Cu" "B.Mask" "B.Paste")
			(net "PWRGD_CHB_CPU1_DIMM")
		)
		(pad "2" smd circle
			(at -0.40005 0)
			(size 0 0)
			(layers "B.Cu" "B.Mask" "B.Paste")
			(net "PWRGD_CHAF_CPU1")
		)
	)
	(footprint ""
		(layer "B.Cu")
		(at 305.778408 -395.148562 90)
		(property "Reference" "C526"
			(at 0 0 90)
			(layer "B.SilkS")
			(hide yes)
			(effects
				(font
					(size 1.27 1.27)
				)
				(justify mirror)
			)
		)
		(property "Value" ""
			(at 0 0 90)
			(layer "B.Fab")
			(effects
				(font
					(size 1.27 1.27)
				)
				(justify mirror)
			)
		)
		(duplicate_pad_numbers_are_jumpers no)
		(fp_line
			(start 0.299974 -0.150114)
			(end -0.299974 -0.150114)
			(stroke
				(width 0.1)
				(type default)
			)
			(layer "B.Fab")
		)
		(fp_line
			(start -0.299974 -0.150114)
			(end -0.299974 0.150114)
			(stroke
				(width 0.1)
				(type default)
			)
			(layer "B.Fab")
		)
		(fp_line
			(start 0.299974 0.150114)
			(end 0.299974 -0.150114)
			(stroke
				(width 0.1)
				(type default)
			)
			(layer "B.Fab")
		)
		(fp_line
			(start -0.299974 0.150114)
			(end 0.299974 0.150114)
			(stroke
				(width 0.1)
				(type default)
			)
			(layer "B.Fab")
		)
		(pad "1" smd rect
			(at 0.2667 0 270)
			(size 0.3048 0.381)
			(layers "B.Cu" "B.Mask" "B.Paste")
			(net "P0V9_CPU0_RT0_2A")
		)
		(pad "2" smd rect
			(at -0.2667 0 270)
			(size 0.3048 0.381)
			(layers "B.Cu" "B.Mask" "B.Paste")
			(net "GND")
		)
	)
	(footprint ""
		(layer "B.Cu")
		(at 199.517 -134.874 -90)
		(property "Reference" "R8106"
			(at 0 0 90)
			(layer "B.SilkS")
			(hide yes)
			(effects
				(font
					(size 1.27 1.27)
				)
				(justify mirror)
			)
		)
		(property "Value" ""
			(at 0 0 90)
			(layer "B.Fab")
			(effects
				(font
					(size 1.27 1.27)
				)
				(justify mirror)
			)
		)
		(duplicate_pad_numbers_are_jumpers no)
		(fp_line
			(start -0.7874 0.4064)
			(end 0.7874 0.4064)
			(stroke
				(width 0.1524)
				(type default)
			)
			(layer "B.SilkS")
		)
		(fp_line
			(start 0.7874 0.4064)
			(end 0.7874 -0.4064)
			(stroke
				(width 0.1524)
				(type default)
			)
			(layer "B.SilkS")
		)
		(fp_line
			(start -0.7874 -0.4064)
			(end -0.7874 0.4064)
			(stroke
				(width 0.1524)
				(type default)
			)
			(layer "B.SilkS")
		)
		(fp_line
			(start 0.7874 -0.4064)
			(end -0.7874 -0.4064)
			(stroke
				(width 0.1524)
				(type default)
			)
			(layer "B.SilkS")
		)
		(fp_line
			(start -0.67945 0.3048)
			(end -0.120396 0.3048)
			(stroke
				(width 0.1)
				(type default)
			)
			(layer "B.Fab")
		)
		(fp_line
			(start -0.120396 0.3048)
			(end -0.120396 0.2794)
			(stroke
				(width 0.1)
				(type default)
			)
			(layer "B.Fab")
		)
		(fp_line
			(start 0.12065 0.3048)
			(end 0.67945 0.3048)
			(stroke
				(width 0.1)
				(type default)
			)
			(layer "B.Fab")
		)
		(fp_line
			(start 0.67945 0.3048)
			(end 0.67945 -0.305054)
			(stroke
				(width 0.1)
				(type default)
			)
			(layer "B.Fab")
		)
		(fp_line
			(start -0.120396 0.2794)
			(end 0.12065 0.2794)
			(stroke
				(width 0.1)
				(type default)
			)
			(layer "B.Fab")
		)
		(fp_line
			(start 0.12065 0.2794)
			(end 0.12065 0.3048)
			(stroke
				(width 0.1)
				(type default)
			)
			(layer "B.Fab")
		)
		(fp_line
			(start -0.12065 -0.2794)
			(end -0.12065 -0.3048)
			(stroke
				(width 0.1)
				(type default)
			)
			(layer "B.Fab")
		)
		(fp_line
			(start 0.12065 -0.2794)
			(end -0.12065 -0.2794)
			(stroke
				(width 0.1)
				(type default)
			)
			(layer "B.Fab")
		)
		(fp_line
			(start -0.67945 -0.3048)
			(end -0.67945 0.3048)
			(stroke
				(width 0.1)
				(type default)
			)
			(layer "B.Fab")
		)
		(fp_line
			(start -0.12065 -0.3048)
			(end -0.67945 -0.3048)
			(stroke
				(width 0.1)
				(type default)
			)
			(layer "B.Fab")
		)
		(fp_line
			(start 0.12065 -0.305054)
			(end 0.12065 -0.2794)
			(stroke
				(width 0.1)
				(type default)
			)
			(layer "B.Fab")
		)
		(fp_line
			(start 0.67945 -0.305054)
			(end 0.12065 -0.305054)
			(stroke
				(width 0.1)
				(type default)
			)
			(layer "B.Fab")
		)
		(pad "1" smd circle
			(at 0.40005 0 90)
			(size 0 0)
			(layers "B.Cu" "B.Mask" "B.Paste")
			(net "P3V3_AUX")
		)
		(pad "2" smd circle
			(at -0.40005 0 90)
			(size 0 0)
			(layers "B.Cu" "B.Mask" "B.Paste")
			(net "FM_AC_PWR_BTN_PLD_ISO_N")
		)
	)
)
